# T6G (Grand Teton) — schematic netlist excerpt (pin names and nets, part order shuffled) for the footprints in the layout excerpt that follows; sources: Cadence DE-HDL packaged netlist, KiCad conversion of 04192023_DAF0TMB3IC0_F0TG_MB_C_brd_V02_OCP.brd

C428  Q_CAP  0.1UF 10V 10% X7S  pkg C0201  page 345 : A = P0V9_CPU1_RT2_2A ; B = GND
R440  Q_RES  4.7K 5% EMPTY  pkg 0402LF  page 28 : A = GND ; B = CPU0_PWR_GD_OUT
R530  Q_RES  0 5% CHIP  pkg 0402LF  page 85 : A = RST_CPU0_RESETL_N ; B = RST_CPU1_RESETL_N

(kicad_pcb
	(version 20260206)
	(generator "pcbnew")
	(generator_version "10.0")
	(general
		(thickness 1.6)
		(legacy_teardrops no)
	)
	(paper "A4")
	(title_block
		(title "04192023_DAF0TMB3IC0_F0TG_MB_C_brd_V02_OCP.brd")
		(comment 1 "Grand Teton / footprints 7520-7522 of 8354")
	)
	(layers
		(0 "F.Cu" signal "TOP")
		(4 "In1.Cu" signal "GND")
		(6 "In2.Cu" signal "IN1")
		(8 "In3.Cu" signal "GND1")
		(10 "In4.Cu" signal "IN2")
		(12 "In5.Cu" signal "GND2")
		(14 "In6.Cu" signal "IN3")
		(16 "In7.Cu" signal "GND3")
		(18 "In8.Cu" signal "VCC")
		(20 "In9.Cu" signal "VCC1")
		(22 "In10.Cu" signal "GND4")
		(24 "In11.Cu" signal "IN4")
		(26 "In12.Cu" signal "GND5")
		(28 "In13.Cu" signal "IN5")
		(30 "In14.Cu" signal "GND6")
		(32 "In15.Cu" signal "IN6")
		(34 "In16.Cu" signal "GND7")
		(2 "B.Cu" signal "BOTTOM")
		(9 "F.Adhes" user "F.Adhesive")
		(11 "B.Adhes" user "B.Adhesive")
		(13 "F.Paste" user "Package Geometry/Pastemask Top")
		(15 "B.Paste" user "Package Geometry/Pastemask Bottom")
		(5 "F.SilkS" user "Ref Des/Silkscreen Top")
		(7 "B.SilkS" user "Ref Des/Silkscreen Bottom")
		(1 "F.Mask" user "Board Geometry/Soldermask Top")
		(3 "B.Mask" user "Board Geometry/Soldermask Bottom")
		(17 "Dwgs.User" user "User.Drawings")
		(19 "Cmts.User" user "User.Comments")
		(21 "Eco1.User" user "User.Eco1")
		(23 "Eco2.User" user "User.Eco2")
		(25 "Edge.Cuts" user "Board Geometry/Outline")
		(27 "Margin" user)
		(31 "F.CrtYd" user "Package Geometry/Place Bound Top")
		(29 "B.CrtYd" user "Package Geometry/Place Bound Bottom")
		(35 "F.Fab" user "Ref Des/Assembly Top")
		(33 "B.Fab" user "Ref Des/Assembly Bottom")
	)
	(footprint ""
		(layer "B.Cu")
		(at 70.172834 -201.672952)
		(property "Reference" "R530"
			(at 0 0 0)
			(layer "B.SilkS")
			(hide yes)
			(effects
				(font
					(size 1.27 1.27)
				)
				(justify mirror)
			)
		)
		(property "Value" ""
			(at 0 0 0)
			(layer "B.Fab")
			(effects
				(font
					(size 1.27 1.27)
				)
				(justify mirror)
			)
		)
		(duplicate_pad_numbers_are_jumpers no)
		(fp_line
			(start -0.7874 -0.4064)
			(end -0.7874 0.4064)
			(stroke
				(width 0.1524)
				(type default)
			)
			(layer "B.SilkS")
		)
		(fp_line
			(start -0.7874 0.4064)
			(end 0.7874 0.4064)
			(stroke
				(width 0.1524)
				(type default)
			)
			(layer "B.SilkS")
		)
		(fp_line
			(start 0.7874 -0.4064)
			(end -0.7874 -0.4064)
			(stroke
				(width 0.1524)
				(type default)
			)
			(layer "B.SilkS")
		)
		(fp_line
			(start 0.7874 0.4064)
			(end 0.7874 -0.4064)
			(stroke
				(width 0.1524)
				(type default)
			)
			(layer "B.SilkS")
		)
		(fp_line
			(start -0.67945 -0.3048)
			(end -0.67945 0.3048)
			(stroke
				(width 0.1)
				(type default)
			)
			(layer "B.Fab")
		)
		(fp_line
			(start -0.67945 0.3048)
			(end -0.120396 0.3048)
			(stroke
				(width 0.1)
				(type default)
			)
			(layer "B.Fab")
		)
		(fp_line
			(start -0.12065 -0.3048)
			(end -0.67945 -0.3048)
			(stroke
				(width 0.1)
				(type default)
			)
			(layer "B.Fab")
		)
		(fp_line
			(start -0.12065 -0.2794)
			(end -0.12065 -0.3048)
			(stroke
				(width 0.1)
				(type default)
			)
			(layer "B.Fab")
		)
		(fp_line
			(start -0.120396 0.2794)
			(end 0.12065 0.2794)
			(stroke
				(width 0.1)
				(type default)
			)
			(layer "B.Fab")
		)
		(fp_line
			(start -0.120396 0.3048)
			(end -0.120396 0.2794)
			(stroke
				(width 0.1)
				(type default)
			)
			(layer "B.Fab")
		)
		(fp_line
			(start 0.12065 -0.305054)
			(end 0.12065 -0.2794)
			(stroke
				(width 0.1)
				(type default)
			)
			(layer "B.Fab")
		)
		(fp_line
			(start 0.12065 -0.2794)
			(end -0.12065 -0.2794)
			(stroke
				(width 0.1)
				(type default)
			)
			(layer "B.Fab")
		)
		(fp_line
			(start 0.12065 0.2794)
			(end 0.12065 0.3048)
			(stroke
				(width 0.1)
				(type default)
			)
			(layer "B.Fab")
		)
		(fp_line
			(start 0.12065 0.3048)
			(end 0.67945 0.3048)
			(stroke
				(width 0.1)
				(type default)
			)
			(layer "B.Fab")
		)
		(fp_line
			(start 0.67945 -0.305054)
			(end 0.12065 -0.305054)
			(stroke
				(width 0.1)
				(type default)
			)
			(layer "B.Fab")
		)
		(fp_line
			(start 0.67945 0.3048)
			(end 0.67945 -0.305054)
			(stroke
				(width 0.1)
				(type default)
			)
			(layer "B.Fab")
		)
		(pad "1" smd circle
			(at 0.40005 0 180)
			(size 0 0)
			(layers "B.Cu" "B.Mask" "B.Paste")
			(net "RST_CPU0_RESETL_N")
		)
		(pad "2" smd circle
			(at -0.40005 0 180)
			(size 0 0)
			(layers "B.Cu" "B.Mask" "B.Paste")
			(net "RST_CPU1_RESETL_N")
		)
	)
	(footprint ""
		(layer "B.Cu")
		(at 148.34616 -388.011162 -90)
		(property "Reference" "C428"
			(at 0 0 90)
			(layer "B.SilkS")
			(hide yes)
			(effects
				(font
					(size 1.27 1.27)
				)
				(justify mirror)
			)
		)
		(property "Value" ""
			(at 0 0 90)
			(layer "B.Fab")
			(effects
				(font
					(size 1.27 1.27)
				)
				(justify mirror)
			)
		)
		(duplicate_pad_numbers_are_jumpers no)
		(fp_line
			(start -0.299974 0.150114)
			(end 0.299974 0.150114)
			(stroke
				(width 0.1)
				(type default)
			)
			(layer "B.Fab")
		)
		(fp_line
			(start 0.299974 0.150114)
			(end 0.299974 -0.150114)
			(stroke
				(width 0.1)
				(type default)
			)
			(layer "B.Fab")
		)
		(fp_line
			(start -0.299974 -0.150114)
			(end -0.299974 0.150114)
			(stroke
				(width 0.1)
				(type default)
			)
			(layer "B.Fab")
		)
		(fp_line
			(start 0.299974 -0.150114)
			(end -0.299974 -0.150114)
			(stroke
				(width 0.1)
				(type default)
			)
			(layer "B.Fab")
		)
		(pad "1" smd rect
			(at 0.2667 0 90)
			(size 0.3048 0.381)
			(layers "B.Cu" "B.Mask" "B.Paste")
			(net "P0V9_CPU1_RT2_2A")
		)
		(pad "2" smd rect
			(at -0.2667 0 90)
			(size 0.3048 0.381)
			(layers "B.Cu" "B.Mask" "B.Paste")
			(net "GND")
		)
	)
	(footprint ""
		(layer "B.Cu")
		(at 406.698958 -326.894952)
		(property "Reference" "R440"
			(at 0 0 0)
			(layer "B.SilkS")
			(hide yes)
			(effects
				(font
					(size 1.27 1.27)
				)
				(justify mirror)
			)
		)
		(property "Value" ""
			(at 0 0 0)
			(layer "B.Fab")
			(effects
				(font
					(size 1.27 1.27)
				)
				(justify mirror)
			)
		)
		(duplicate_pad_numbers_are_jumpers no)
		(fp_line
			(start -0.7874 -0.4064)
			(end -0.7874 0.4064)
			(stroke
				(width 0.1524)
				(type default)
			)
			(layer "B.SilkS")
		)
		(fp_line
			(start -0.7874 0.4064)
			(end 0.7874 0.4064)
			(stroke
				(width 0.1524)
				(type default)
			)
			(layer "B.SilkS")
		)
		(fp_line
			(start 0.7874 -0.4064)
			(end -0.7874 -0.4064)
			(stroke
				(width 0.1524)
				(type default)
			)
			(layer "B.SilkS")
		)
		(fp_line
			(start 0.7874 0.4064)
			(end 0.7874 -0.4064)
			(stroke
				(width 0.1524)
				(type default)
			)
			(layer "B.SilkS")
		)
		(fp_line
			(start -0.67945 -0.3048)
			(end -0.67945 0.3048)
			(stroke
				(width 0.1)
				(type default)
			)
			(layer "B.Fab")
		)
		(fp_line
			(start -0.67945 0.3048)
			(end -0.120396 0.3048)
			(stroke
				(width 0.1)
				(type default)
			)
			(layer "B.Fab")
		)
		(fp_line
			(start -0.12065 -0.3048)
			(end -0.67945 -0.3048)
			(stroke
				(width 0.1)
				(type default)
			)
			(layer "B.Fab")
		)
		(fp_line
			(start -0.12065 -0.2794)
			(end -0.12065 -0.3048)
			(stroke
				(width 0.1)
				(type default)
			)
			(layer "B.Fab")
		)
		(fp_line
			(start -0.120396 0.2794)
			(end 0.12065 0.2794)
			(stroke
				(width 0.1)
				(type default)
			)
			(layer "B.Fab")
		)
		(fp_line
			(start -0.120396 0.3048)
			(end -0.120396 0.2794)
			(stroke
				(width 0.1)
				(type default)
			)
			(layer "B.Fab")
		)
		(fp_line
			(start 0.12065 -0.305054)
			(end 0.12065 -0.2794)
			(stroke
				(width 0.1)
				(type default)
			)
			(layer "B.Fab")
		)
		(fp_line
			(start 0.12065 -0.2794)
			(end -0.12065 -0.2794)
			(stroke
				(width 0.1)
				(type default)
			)
			(layer "B.Fab")
		)
		(fp_line
			(start 0.12065 0.2794)
			(end 0.12065 0.3048)
			(stroke
				(width 0.1)
				(type default)
			)
			(layer "B.Fab")
		)
		(fp_line
			(start 0.12065 0.3048)
			(end 0.67945 0.3048)
			(stroke
				(width 0.1)
				(type default)
			)
			(layer "B.Fab")
		)
		(fp_line
			(start 0.67945 -0.305054)
			(end 0.12065 -0.305054)
			(stroke
				(width 0.1)
				(type default)
			)
			(layer "B.Fab")
		)
		(fp_line
			(start 0.67945 0.3048)
			(end 0.67945 -0.305054)
			(stroke
				(width 0.1)
				(type default)
			)
			(layer "B.Fab")
		)
		(pad "1" smd circle
			(at 0.40005 0 180)
			(size 0 0)
			(layers "B.Cu" "B.Mask" "B.Paste")
			(net "GND")
		)
		(pad "2" smd circle
			(at -0.40005 0 180)
			(size 0 0)
			(layers "B.Cu" "B.Mask" "B.Paste")
			(net "CPU0_PWR_GD_OUT")
		)
	)
)
